# BASEBOARD_FAB2 (Tioga Pass) — schematic netlist excerpt (pin names and nets, part order shuffled) for the footprints in the layout excerpt that follows; sources: Cadence DE-HDL packaged netlist, KiCad conversion of Wiwynn_Tioga_Pass_MB.brd

EU7G3  IR354XX  IR35411 IC  pkg SM  page 216
  VOS  = PVDDQ_ABC
  LGND  = GND
  VCC  = VR_PVDDQ_ABC_PH2_VCIN
  VDRV  = P5V_STBY
  PGND(0)  = GND
  GL(0)  = TP_PVDDQ_ABC_PH2_GL_0
  PGND(1)  = GND
  SW  = VR_PVDDQ_ABC_PH2_SW
  VIN(0)  = VR_FET_SW_P12V_STBY_PVDDQ_ABC
  VIN(1)  = VR_FET_SW_P12V_STBY_PVDDQ_ABC
  NC  = NC
  PHASE  = VR_PVDDQ_ABC_PH2_PHASE
  BOOST  = VR_PVDDQ_ABC_PH2_BOOT_R
  PWM  = VR_PVDDQ_ABC_PWM2
  EN  = P5V_STBY
  TOUT_FLT  = A_TSENSE_PVDDQ_ABC
  OCSET  = VR_PVDDQ_ABC_PH2_OCSET
  IOUT  = ISENSE_PVDDQ_ABC_PH2_IMON
  REFIN  = VR_PVDDQ_ABC_AIREF2
  PGND(2)  = GND
  GL(1)  = TP_PVDDQ_ABC_PH2_GL_1

(kicad_pcb
	(version 20260206)
	(generator "pcbnew")
	(generator_version "10.0")
	(general
		(thickness 1.6)
		(legacy_teardrops no)
	)
	(paper "A4")
	(title_block
		(title "Wiwynn_Tioga_Pass_MB.brd")
		(comment 1 "Tioga Pass / footprints 1393-1393 of 4770")
	)
	(layers
		(0 "F.Cu" signal "TOP")
		(4 "In1.Cu" signal "L2GND")
		(6 "In2.Cu" signal "L3")
		(8 "In3.Cu" signal "L4GND")
		(10 "In4.Cu" signal "L5")
		(12 "In5.Cu" signal "L6GND")
		(14 "In6.Cu" signal "L7VCC")
		(16 "In7.Cu" signal "L8VCC")
		(18 "In8.Cu" signal "L9GND")
		(20 "In9.Cu" signal "L10")
		(22 "In10.Cu" signal "L11GND")
		(24 "In11.Cu" signal "L12")
		(26 "In12.Cu" signal "L13GND")
		(2 "B.Cu" signal "BOTTOM")
		(9 "F.Adhes" user "F.Adhesive")
		(11 "B.Adhes" user "B.Adhesive")
		(13 "F.Paste" user "Package Geometry/Pastemask Top")
		(15 "B.Paste" user "Package Geometry/Pastemask Bottom")
		(5 "F.SilkS" user "Ref Des/Silkscreen Top")
		(7 "B.SilkS" user "Ref Des/Silkscreen Bottom")
		(1 "F.Mask" user "Board Geometry/Soldermask Top")
		(3 "B.Mask" user "Board Geometry/Soldermask Bottom")
		(17 "Dwgs.User" user "User.Drawings")
		(19 "Cmts.User" user "User.Comments")
		(21 "Eco1.User" user "User.Eco1")
		(23 "Eco2.User" user "User.Eco2")
		(25 "Edge.Cuts" user "Board Geometry/Outline")
		(27 "Margin" user)
		(31 "F.CrtYd" user "Package Geometry/Place Bound Top")
		(29 "B.CrtYd" user "Package Geometry/Place Bound Bottom")
		(35 "F.Fab" user "Ref Des/Assembly Top")
		(33 "B.Fab" user "Ref Des/Assembly Bottom")
	)
	(footprint ""
		(layer "F.Cu")
		(at 346.3671 1.741678 -90)
		(property "Reference" "EU7G3"
			(at 3.675888 2.504694 0)
			(unlocked yes)
			(layer "F.SilkS")
			(effects
				(font
					(size 0.7874 0.5842)
					(thickness 0.1524)
				)
			)
		)
		(property "Value" ""
			(at 0 0 270)
			(layer "F.Fab")
			(effects
				(font
					(size 1.27 1.27)
				)
			)
		)
		(duplicate_pad_numbers_are_jumpers no)
		(fp_line
			(start -3.0099 3.429)
			(end -3.0099 -3.5052)
			(stroke
				(width 0.1524)
				(type default)
			)
			(layer "F.SilkS")
		)
		(fp_line
			(start 2.9718 3.429)
			(end -3.0099 3.429)
			(stroke
				(width 0.1524)
				(type default)
			)
			(layer "F.SilkS")
		)
		(fp_line
			(start -3.0099 -3.5052)
			(end 2.9718 -3.5052)
			(stroke
				(width 0.1524)
				(type default)
			)
			(layer "F.SilkS")
		)
		(fp_line
			(start 2.9718 -3.5052)
			(end 2.9718 3.429)
			(stroke
				(width 0.1524)
				(type default)
			)
			(layer "F.SilkS")
		)
		(fp_circle
			(center -3.057398 -2.678684)
			(end -3.057398 -2.805684)
			(stroke
				(width 0.254)
				(type default)
			)
			(fill no)
			(layer "F.SilkS")
		)
		(fp_poly
			(pts
				(xy -2.9972 -3.4925) (xy -2.9972 -2.6924) (xy -2.1971 -3.4925)
			)
			(stroke
				(width 0)
				(type default)
			)
			(fill yes)
			(layer "F.SilkS")
		)
		(fp_poly
			(pts
				(xy -2.549906 -3.050032) (xy -2.549906 3.050032) (xy 2.549906 3.050032) (xy 2.549906 -3.050032)
			)
			(stroke
				(width 0)
				(type default)
			)
			(fill no)
			(layer "F.CrtYd")
		)
		(fp_line
			(start -2.549906 3.050032)
			(end -2.549906 -3.050032)
			(stroke
				(width 0.1)
				(type default)
			)
			(layer "F.Fab")
		)
		(fp_line
			(start 2.549906 3.050032)
			(end -2.549906 3.050032)
			(stroke
				(width 0.1)
				(type default)
			)
			(layer "F.Fab")
		)
		(fp_line
			(start -2.549906 -3.050032)
			(end 2.549906 -3.050032)
			(stroke
				(width 0.1)
				(type default)
			)
			(layer "F.Fab")
		)
		(fp_line
			(start 2.549906 -3.050032)
			(end 2.549906 3.050032)
			(stroke
				(width 0.1)
				(type default)
			)
			(layer "F.Fab")
		)
		(fp_circle
			(center -3.057398 -2.678684)
			(end -3.057398 -2.805684)
			(stroke
				(width 0.254)
				(type default)
			)
			(fill no)
			(layer "F.Fab")
		)
		(pad "1" smd rect
			(at -2.39522 -2.279904 270)
			(size 0.7112 0.254)
			(layers "F.Cu" "F.Mask" "F.Paste")
			(net "PVDDQ_ABC")
		)
		(pad "2" smd rect
			(at -2.39522 -1.83007 270)
			(size 0.7112 0.254)
			(layers "F.Cu" "F.Mask" "F.Paste")
			(net "GND")
		)
		(pad "3" smd rect
			(at -2.39522 -1.379982 270)
			(size 0.7112 0.254)
			(layers "F.Cu" "F.Mask" "F.Paste")
			(net "VR_PVDDQ_ABC_PH2_VCIN")
		)
		(pad "4" smd rect
			(at -2.39522 -0.929894 270)
			(size 0.7112 0.254)
			(layers "F.Cu" "F.Mask" "F.Paste")
			(net "P5V_STBY")
		)
		(pad "5" smd rect
			(at -2.39522 -0.48006 270)
			(size 0.7112 0.254)
			(layers "F.Cu" "F.Mask" "F.Paste")
			(net "GND")
		)
		(pad "6" smd rect
			(at -2.39522 -0.029972 270)
			(size 0.7112 0.254)
			(layers "F.Cu" "F.Mask" "F.Paste")
			(net "TP_PVDDQ_ABC_PH2_GL_0")
		)
		(pad "7" smd custom
			(at 0.016764 1.145032 270)
			(size 0.53975 0.53975)
			(layers "F.Cu" "F.Mask" "F.Paste")
			(net "GND")
			(options
				(clearance outline)
				(anchor circle)
			)
			(primitives
				(gr_poly
					(pts
						(xy -2.7051 1.0795) (xy -2.7051 -0.3683) (xy -0.9271 -0.3683) (xy -0.9271 -1.0795) (xy 2.7051 -1.0795)
						(xy 2.7051 1.0795)
					)
					(width 0)
					(fill yes)
				)
			)
		)
		(pad "10" smd rect
			(at -0.008382 2.874772 270)
			(size 4.3434 0.6096)
			(layers "F.Cu" "F.Mask" "F.Paste")
			(net "VR_PVDDQ_ABC_PH2_SW")
		)
		(pad "25" smd rect
			(at 1.548384 -1.283208 270)
			(size 2.3368 2.0066)
			(layers "F.Cu" "F.Mask" "F.Paste")
			(net "VR_FET_SW_P12V_STBY_PVDDQ_ABC")
		)
		(pad "30" smd rect
			(at 2.050034 -2.895092 270)
			(size 0.254 0.7112)
			(layers "F.Cu" "F.Mask" "F.Paste")
			(net "VR_FET_SW_P12V_STBY_PVDDQ_ABC")
		)
		(pad "31" smd rect
			(at 1.599946 -2.895092 270)
			(size 0.254 0.7112)
			(layers "F.Cu" "F.Mask" "F.Paste")
			(net "Net_369")
		)
		(pad "32" smd rect
			(at 1.150112 -2.895092 270)
			(size 0.254 0.7112)
			(layers "F.Cu" "F.Mask" "F.Paste")
			(net "VR_PVDDQ_ABC_PH2_PHASE")
		)
		(pad "33" smd rect
			(at 0.700024 -2.895092 270)
			(size 0.254 0.7112)
			(layers "F.Cu" "F.Mask" "F.Paste")
			(net "VR_PVDDQ_ABC_PH2_BOOT_R")
		)
		(pad "34" smd rect
			(at 0.249936 -2.895092 270)
			(size 0.254 0.7112)
			(layers "F.Cu" "F.Mask" "F.Paste")
			(net "VR_PVDDQ_ABC_PWM2")
		)
		(pad "35" smd rect
			(at -0.199898 -2.895092 270)
			(size 0.254 0.7112)
			(layers "F.Cu" "F.Mask" "F.Paste")
			(net "P5V_STBY")
		)
		(pad "36" smd rect
			(at -0.649986 -2.895092 270)
			(size 0.254 0.7112)
			(layers "F.Cu" "F.Mask" "F.Paste")
			(net "A_TSENSE_PVDDQ_ABC")
		)
		(pad "37" smd rect
			(at -1.100074 -2.895092 270)
			(size 0.254 0.7112)
			(layers "F.Cu" "F.Mask" "F.Paste")
			(net "VR_PVDDQ_ABC_PH2_OCSET")
		)
		(pad "38" smd rect
			(at -1.549908 -2.895092 270)
			(size 0.254 0.7112)
			(layers "F.Cu" "F.Mask" "F.Paste")
			(net "ISENSE_PVDDQ_ABC_PH2_IMON")
		)
		(pad "39" smd rect
			(at -1.999996 -2.895092 270)
			(size 0.254 0.7112)
			(layers "F.Cu" "F.Mask" "F.Paste")
			(net "VR_PVDDQ_ABC_AIREF2")
		)
		(pad "40" smd rect
			(at -0.871728 -1.283208 270)
			(size 1.8034 2.0066)
			(layers "F.Cu" "F.Mask" "F.Paste")
			(net "GND")
		)
		(pad "41" smd rect
			(at -1.533906 0.247904 270)
			(size 0.508 0.3556)
			(layers "F.Cu" "F.Mask" "F.Paste")
			(net "TP_PVDDQ_ABC_PH2_GL_1")
		)
	)
)
